(kicad_pcb
	(version 20260206)
	(generator "pcbnew")
	(generator_version "10.0")
	(general
		(thickness 1.6)
		(legacy_teardrops no)
	)
	(paper "A4")
	(title_block
		(title "v1-chassis-manager — T6M_CM_d_v01_1031_1645.brd")
		(comment 1 "Open CloudServer (Microsoft) / footprints 2003-2012 of 2512")
	)
	(layers
		(0 "F.Cu" signal "TOP")
		(4 "In1.Cu" signal "GND1")
		(6 "In2.Cu" signal "IN1")
		(8 "In3.Cu" signal "VCC1")
		(10 "In4.Cu" signal "VCC2")
		(12 "In5.Cu" signal "GND2")
		(14 "In6.Cu" signal "IN2")
		(16 "In7.Cu" signal "IN3")
		(18 "In8.Cu" signal "GND3")
		(2 "B.Cu" signal "BOTTOM")
		(9 "F.Adhes" user "F.Adhesive")
		(11 "B.Adhes" user "B.Adhesive")
		(13 "F.Paste" user "Package Geometry/Pastemask Top")
		(15 "B.Paste" user "Package Geometry/Pastemask Bottom")
		(5 "F.SilkS" user "Ref Des/Silkscreen Top")
		(7 "B.SilkS" user "Ref Des/Silkscreen Bottom")
		(1 "F.Mask" user "Board Geometry/Soldermask Top")
		(3 "B.Mask" user "Board Geometry/Soldermask Bottom")
		(17 "Dwgs.User" user "User.Drawings")
		(19 "Cmts.User" user "User.Comments")
		(21 "Eco1.User" user "User.Eco1")
		(23 "Eco2.User" user "User.Eco2")
		(25 "Edge.Cuts" user "Board Geometry/Outline")
		(27 "Margin" user)
		(31 "F.CrtYd" user "Package Geometry/Place Bound Top")
		(29 "B.CrtYd" user "Package Geometry/Place Bound Bottom")
		(35 "F.Fab" user "Ref Des/Assembly Top")
		(33 "B.Fab" user "Ref Des/Assembly Bottom")
	)
	(footprint ""
		(layer "B.Cu")
		(at 76.05776 -188.126624 -90)
		(property "Reference" "C655"
			(at -4.318254 0.3683 270)
			(unlocked yes)
			(layer "B.SilkS")
			(effects
				(font
					(size 0.7874 0.5842)
					(thickness 0.1524)
				)
				(justify left mirror)
			)
		)
		(property "Value" ""
			(at 0 0 90)
			(layer "B.Fab")
			(effects
				(font
					(size 1.27 1.27)
				)
				(justify mirror)
			)
		)
		(duplicate_pad_numbers_are_jumpers no)
		(fp_line
			(start -0.7874 0.4064)
			(end 0.7874 0.4064)
			(stroke
				(width 0.1524)
				(type default)
			)
			(layer "B.SilkS")
		)
		(fp_line
			(start 0.7874 0.4064)
			(end 0.7874 -0.4064)
			(stroke
				(width 0.1524)
				(type default)
			)
			(layer "B.SilkS")
		)
		(fp_line
			(start 0 0.381)
			(end 0 -0.381)
			(stroke
				(width 0.1524)
				(type default)
			)
			(layer "B.SilkS")
		)
		(fp_line
			(start -0.7874 -0.4064)
			(end -0.7874 0.4064)
			(stroke
				(width 0.1524)
				(type default)
			)
			(layer "B.SilkS")
		)
		(fp_line
			(start 0.7874 -0.4064)
			(end -0.7874 -0.4064)
			(stroke
				(width 0.1524)
				(type default)
			)
			(layer "B.SilkS")
		)
		(fp_poly
			(pts
				(xy 0.5334 0.254) (xy 0.635 0.254) (xy 0.635 0.2286) (xy 0.635 -0.254) (xy 0.5334 -0.254) (xy 0.5334 -0.2794)
				(xy -0.5334 -0.2794) (xy -0.5334 -0.254) (xy -0.635 -0.254) (xy -0.635 0.254) (xy -0.5334 0.254)
				(xy -0.5334 0.2794) (xy 0.508 0.2794) (xy 0.5334 0.2794)
			)
			(stroke
				(width 0)
				(type default)
			)
			(fill no)
			(layer "B.CrtYd")
		)
		(pad "1" smd rect
			(at -0.40005 0 90)
			(size 0.4572 0.508)
			(layers "B.Cu" "B.Mask" "B.Paste")
			(net "T3_NODE4_EN_R")
		)
		(pad "2" smd rect
			(at 0.40005 0 90)
			(size 0.4572 0.508)
			(layers "B.Cu" "B.Mask" "B.Paste")
			(net "GND")
		)
	)
	(footprint ""
		(layer "B.Cu")
		(at 181.803294 -159.333692 -90)
		(property "Reference" "C524"
			(at -2.625598 0.04445 270)
			(unlocked yes)
			(layer "B.SilkS")
			(effects
				(font
					(size 0.7874 0.5842)
					(thickness 0.1524)
				)
				(justify left mirror)
			)
		)
		(property "Value" ""
			(at 0 0 90)
			(layer "B.Fab")
			(effects
				(font
					(size 1.27 1.27)
				)
				(justify mirror)
			)
		)
		(duplicate_pad_numbers_are_jumpers no)
		(fp_line
			(start -0.7874 0.406146)
			(end 0.7874 0.406146)
			(stroke
				(width 0.1524)
				(type default)
			)
			(layer "B.SilkS")
		)
		(fp_line
			(start 0.7874 0.406146)
			(end 0.7874 -0.406146)
			(stroke
				(width 0.1524)
				(type default)
			)
			(layer "B.SilkS")
		)
		(fp_line
			(start 0 0.381)
			(end 0 -0.381)
			(stroke
				(width 0.1524)
				(type default)
			)
			(layer "B.SilkS")
		)
		(fp_line
			(start -0.7874 -0.406146)
			(end -0.7874 0.406146)
			(stroke
				(width 0.1524)
				(type default)
			)
			(layer "B.SilkS")
		)
		(fp_line
			(start 0.7874 -0.406146)
			(end -0.7874 -0.406146)
			(stroke
				(width 0.1524)
				(type default)
			)
			(layer "B.SilkS")
		)
		(fp_poly
			(pts
				(xy 0.5334 0.254) (xy 0.635 0.254) (xy 0.635 0.2286) (xy 0.635 -0.254) (xy 0.5334 -0.254) (xy 0.5334 -0.2794)
				(xy -0.5334 -0.2794) (xy -0.5334 -0.254) (xy -0.635 -0.254) (xy -0.635 0.254) (xy -0.5334 0.254)
				(xy -0.5334 0.2794) (xy 0.508 0.2794) (xy 0.5334 0.2794)
			)
			(stroke
				(width 0)
				(type default)
			)
			(fill no)
			(layer "B.CrtYd")
		)
		(pad "1" smd rect
			(at -0.40005 0 90)
			(size 0.4572 0.508)
			(layers "B.Cu" "B.Mask" "B.Paste")
			(net "P1V9_LAN2")
		)
		(pad "2" smd rect
			(at 0.40005 0 90)
			(size 0.4572 0.508)
			(layers "B.Cu" "B.Mask" "B.Paste")
			(net "GND")
		)
	)
	(footprint ""
		(layer "B.Cu")
		(at 135.196834 -38.391084 180)
		(property "Reference" "R1180"
			(at 5.415788 -18.226532 0)
			(unlocked yes)
			(layer "B.SilkS")
			(effects
				(font
					(size 0.7874 0.5842)
					(thickness 0.1524)
				)
				(justify left mirror)
			)
		)
		(property "Value" ""
			(at 0 0 0)
			(layer "B.Fab")
			(effects
				(font
					(size 1.27 1.27)
				)
				(justify mirror)
			)
		)
		(duplicate_pad_numbers_are_jumpers no)
		(fp_line
			(start 0.7874 0.4064)
			(end 0.7874 -0.4064)
			(stroke
				(width 0.1524)
				(type default)
			)
			(layer "B.SilkS")
		)
		(fp_line
			(start 0.7874 -0.4064)
			(end -0.7874 -0.4064)
			(stroke
				(width 0.1524)
				(type default)
			)
			(layer "B.SilkS")
		)
		(fp_line
			(start -0.7874 0.4064)
			(end 0.7874 0.4064)
			(stroke
				(width 0.1524)
				(type default)
			)
			(layer "B.SilkS")
		)
		(fp_line
			(start -0.7874 -0.4064)
			(end -0.7874 0.4064)
			(stroke
				(width 0.1524)
				(type default)
			)
			(layer "B.SilkS")
		)
		(fp_poly
			(pts
				(xy 0.508 0.2794) (xy 0.508 0.2286) (xy 0.635 0.2286) (xy 0.635 -0.254) (xy 0.5334 -0.254) (xy 0.5334 -0.2794)
				(xy -0.5334 -0.2794) (xy -0.5334 -0.254) (xy -0.635 -0.254) (xy -0.635 0.254) (xy -0.5334 0.254)
				(xy -0.5334 0.2794)
			)
			(stroke
				(width 0)
				(type default)
			)
			(fill no)
			(layer "B.CrtYd")
		)
		(pad "1" smd rect
			(at -0.40005 0)
			(size 0.4572 0.508)
			(layers "B.Cu" "B.Mask" "B.Paste")
			(net "CPLD_WDT3")
		)
		(pad "2" smd rect
			(at 0.40005 0)
			(size 0.4572 0.508)
			(layers "B.Cu" "B.Mask" "B.Paste")
			(net "GND")
		)
	)
	(footprint ""
		(layer "B.Cu")
		(at 61.877448 -85.05444 90)
		(property "Reference" "C76"
			(at 1.0287 0.424942 270)
			(unlocked yes)
			(layer "B.SilkS")
			(effects
				(font
					(size 0.7874 0.5842)
					(thickness 0.1524)
				)
				(justify left mirror)
			)
		)
		(property "Value" ""
			(at 0 0 90)
			(layer "B.Fab")
			(effects
				(font
					(size 1.27 1.27)
				)
				(justify mirror)
			)
		)
		(duplicate_pad_numbers_are_jumpers no)
		(fp_line
			(start 0.7874 -0.4064)
			(end -0.7874 -0.4064)
			(stroke
				(width 0.1524)
				(type default)
			)
			(layer "B.SilkS")
		)
		(fp_line
			(start -0.7874 -0.4064)
			(end -0.7874 0.4064)
			(stroke
				(width 0.1524)
				(type default)
			)
			(layer "B.SilkS")
		)
		(fp_line
			(start 0 0.381)
			(end 0 -0.381)
			(stroke
				(width 0.1524)
				(type default)
			)
			(layer "B.SilkS")
		)
		(fp_line
			(start 0.7874 0.4064)
			(end 0.7874 -0.4064)
			(stroke
				(width 0.1524)
				(type default)
			)
			(layer "B.SilkS")
		)
		(fp_line
			(start -0.7874 0.4064)
			(end 0.7874 0.4064)
			(stroke
				(width 0.1524)
				(type default)
			)
			(layer "B.SilkS")
		)
		(fp_poly
			(pts
				(xy 0.5334 0.254) (xy 0.635 0.254) (xy 0.635 0.2286) (xy 0.635 -0.254) (xy 0.5334 -0.254) (xy 0.5334 -0.2794)
				(xy -0.5334 -0.2794) (xy -0.5334 -0.254) (xy -0.635 -0.254) (xy -0.635 0.254) (xy -0.5334 0.254)
				(xy -0.5334 0.2794) (xy 0.508 0.2794) (xy 0.5334 0.2794)
			)
			(stroke
				(width 0)
				(type default)
			)
			(fill no)
			(layer "B.CrtYd")
		)
		(pad "1" smd rect
			(at -0.40005 0 270)
			(size 0.4572 0.508)
			(layers "B.Cu" "B.Mask" "B.Paste")
			(net "P1V8_SUS_NODE1")
		)
		(pad "2" smd rect
			(at 0.40005 0 270)
			(size 0.4572 0.508)
			(layers "B.Cu" "B.Mask" "B.Paste")
			(net "GND")
		)
	)
	(footprint ""
		(layer "B.Cu")
		(at 126.039626 -40.071294 180)
		(property "Reference" "R620"
			(at -1.493774 -1.235964 0)
			(unlocked yes)
			(layer "B.SilkS")
			(effects
				(font
					(size 0.7874 0.5842)
					(thickness 0.1524)
				)
				(justify left mirror)
			)
		)
		(property "Value" ""
			(at 0 0 0)
			(layer "B.Fab")
			(effects
				(font
					(size 1.27 1.27)
				)
				(justify mirror)
			)
		)
		(duplicate_pad_numbers_are_jumpers no)
		(fp_line
			(start 0.7874 0.4064)
			(end 0.7874 -0.4064)
			(stroke
				(width 0.1524)
				(type default)
			)
			(layer "B.SilkS")
		)
		(fp_line
			(start 0.7874 -0.4064)
			(end -0.7874 -0.4064)
			(stroke
				(width 0.1524)
				(type default)
			)
			(layer "B.SilkS")
		)
		(fp_line
			(start -0.7874 0.4064)
			(end 0.7874 0.4064)
			(stroke
				(width 0.1524)
				(type default)
			)
			(layer "B.SilkS")
		)
		(fp_line
			(start -0.7874 -0.4064)
			(end -0.7874 0.4064)
			(stroke
				(width 0.1524)
				(type default)
			)
			(layer "B.SilkS")
		)
		(fp_poly
			(pts
				(xy 0.508 0.2794) (xy 0.508 0.2286) (xy 0.635 0.2286) (xy 0.635 -0.254) (xy 0.5334 -0.254) (xy 0.5334 -0.2794)
				(xy -0.5334 -0.2794) (xy -0.5334 -0.254) (xy -0.635 -0.254) (xy -0.635 0.254) (xy -0.5334 0.254)
				(xy -0.5334 0.2794)
			)
			(stroke
				(width 0)
				(type default)
			)
			(fill no)
			(layer "B.CrtYd")
		)
		(pad "1" smd rect
			(at -0.40005 0)
			(size 0.4572 0.508)
			(layers "B.Cu" "B.Mask" "B.Paste")
			(net "P3V3_NODE1")
		)
		(pad "2" smd rect
			(at 0.40005 0)
			(size 0.4572 0.508)
			(layers "B.Cu" "B.Mask" "B.Paste")
			(net "SIO_PWROK2")
		)
	)
	(footprint ""
		(layer "B.Cu")
		(at 130.79476 -184.951624 -90)
		(property "Reference" "C731"
			(at -4.354576 2.44983 270)
			(unlocked yes)
			(layer "B.SilkS")
			(effects
				(font
					(size 0.7874 0.5842)
					(thickness 0.1524)
				)
				(justify left mirror)
			)
		)
		(property "Value" ""
			(at 0 0 90)
			(layer "B.Fab")
			(effects
				(font
					(size 1.27 1.27)
				)
				(justify mirror)
			)
		)
		(duplicate_pad_numbers_are_jumpers no)
		(fp_line
			(start -0.7874 0.4064)
			(end 0.7874 0.4064)
			(stroke
				(width 0.1524)
				(type default)
			)
			(layer "B.SilkS")
		)
		(fp_line
			(start 0.7874 0.4064)
			(end 0.7874 -0.4064)
			(stroke
				(width 0.1524)
				(type default)
			)
			(layer "B.SilkS")
		)
		(fp_line
			(start 0 0.381)
			(end 0 -0.381)
			(stroke
				(width 0.1524)
				(type default)
			)
			(layer "B.SilkS")
		)
		(fp_line
			(start -0.7874 -0.4064)
			(end -0.7874 0.4064)
			(stroke
				(width 0.1524)
				(type default)
			)
			(layer "B.SilkS")
		)
		(fp_line
			(start 0.7874 -0.4064)
			(end -0.7874 -0.4064)
			(stroke
				(width 0.1524)
				(type default)
			)
			(layer "B.SilkS")
		)
		(fp_poly
			(pts
				(xy 0.5334 0.254) (xy 0.635 0.254) (xy 0.635 0.2286) (xy 0.635 -0.254) (xy 0.5334 -0.254) (xy 0.5334 -0.2794)
				(xy -0.5334 -0.2794) (xy -0.5334 -0.254) (xy -0.635 -0.254) (xy -0.635 0.254) (xy -0.5334 0.254)
				(xy -0.5334 0.2794) (xy 0.508 0.2794) (xy 0.5334 0.2794)
			)
			(stroke
				(width 0)
				(type default)
			)
			(fill no)
			(layer "B.CrtYd")
		)
		(pad "1" smd rect
			(at -0.40005 0 90)
			(size 0.4572 0.508)
			(layers "B.Cu" "B.Mask" "B.Paste")
			(net "UART_T9_NODE3_RXD")
		)
		(pad "2" smd rect
			(at 0.40005 0 90)
			(size 0.4572 0.508)
			(layers "B.Cu" "B.Mask" "B.Paste")
			(net "GND")
		)
	)
	(footprint ""
		(layer "B.Cu")
		(at 116.44376 -185.205624 90)
		(property "Reference" "R881"
			(at 3.957828 0.575056 270)
			(unlocked yes)
			(layer "B.SilkS")
			(effects
				(font
					(size 0.7874 0.5842)
					(thickness 0.1524)
				)
				(justify left mirror)
			)
		)
		(property "Value" ""
			(at 0 0 90)
			(layer "B.Fab")
			(effects
				(font
					(size 1.27 1.27)
				)
				(justify mirror)
			)
		)
		(duplicate_pad_numbers_are_jumpers no)
		(fp_line
			(start 0.7874 -0.4064)
			(end -0.7874 -0.4064)
			(stroke
				(width 0.1524)
				(type default)
			)
			(layer "B.SilkS")
		)
		(fp_line
			(start -0.7874 -0.4064)
			(end -0.7874 0.4064)
			(stroke
				(width 0.1524)
				(type default)
			)
			(layer "B.SilkS")
		)
		(fp_line
			(start 0.7874 0.4064)
			(end 0.7874 -0.4064)
			(stroke
				(width 0.1524)
				(type default)
			)
			(layer "B.SilkS")
		)
		(fp_line
			(start -0.7874 0.4064)
			(end 0.7874 0.4064)
			(stroke
				(width 0.1524)
				(type default)
			)
			(layer "B.SilkS")
		)
		(fp_poly
			(pts
				(xy 0.508 0.2794) (xy 0.508 0.2286) (xy 0.635 0.2286) (xy 0.635 -0.254) (xy 0.5334 -0.254) (xy 0.5334 -0.2794)
				(xy -0.5334 -0.2794) (xy -0.5334 -0.254) (xy -0.635 -0.254) (xy -0.635 0.254) (xy -0.5334 0.254)
				(xy -0.5334 0.2794)
			)
			(stroke
				(width 0)
				(type default)
			)
			(fill no)
			(layer "B.CrtYd")
		)
		(pad "1" smd rect
			(at -0.40005 0 270)
			(size 0.4572 0.508)
			(layers "B.Cu" "B.Mask" "B.Paste")
			(net "T7_NODE4_EN")
		)
		(pad "2" smd rect
			(at 0.40005 0 270)
			(size 0.4572 0.508)
			(layers "B.Cu" "B.Mask" "B.Paste")
			(net "T7_NODE4_EN_R")
		)
	)
	(footprint ""
		(layer "B.Cu")
		(at 16.250666 -134.106158)
		(property "Reference" "PR25"
			(at 3.271012 -1.273556 0)
			(unlocked yes)
			(layer "B.SilkS")
			(effects
				(font
					(size 0.7874 0.5842)
					(thickness 0.1524)
				)
				(justify left mirror)
			)
		)
		(property "Value" ""
			(at 0 0 0)
			(layer "B.Fab")
			(effects
				(font
					(size 1.27 1.27)
				)
				(justify mirror)
			)
		)
		(duplicate_pad_numbers_are_jumpers no)
		(fp_line
			(start -0.7874 -0.4064)
			(end -0.7874 0.4064)
			(stroke
				(width 0.1524)
				(type default)
			)
			(layer "B.SilkS")
		)
		(fp_line
			(start -0.7874 0.4064)
			(end 0.7874 0.4064)
			(stroke
				(width 0.1524)
				(type default)
			)
			(layer "B.SilkS")
		)
		(fp_line
			(start 0.7874 -0.4064)
			(end -0.7874 -0.4064)
			(stroke
				(width 0.1524)
				(type default)
			)
			(layer "B.SilkS")
		)
		(fp_line
			(start 0.7874 0.4064)
			(end 0.7874 -0.4064)
			(stroke
				(width 0.1524)
				(type default)
			)
			(layer "B.SilkS")
		)
		(fp_poly
			(pts
				(xy 0.508 0.2794) (xy 0.508 0.2286) (xy 0.635 0.2286) (xy 0.635 -0.254) (xy 0.5334 -0.254) (xy 0.5334 -0.2794)
				(xy -0.5334 -0.2794) (xy -0.5334 -0.254) (xy -0.635 -0.254) (xy -0.635 0.254) (xy -0.5334 0.254)
				(xy -0.5334 0.2794)
			)
			(stroke
				(width 0)
				(type default)
			)
			(fill no)
			(layer "B.CrtYd")
		)
		(pad "1" smd rect
			(at -0.40005 0 180)
			(size 0.4572 0.508)
			(layers "B.Cu" "B.Mask" "B.Paste")
			(net "P3V3_NODE1")
		)
		(pad "2" smd rect
			(at 0.40005 0 180)
			(size 0.4572 0.508)
			(layers "B.Cu" "B.Mask" "B.Paste")
			(net "P1V05_NODE1_VREFIN")
		)
	)
	(footprint ""
		(layer "B.Cu")
		(at 63.832486 -118.783862 -90)
		(property "Reference" "R320"
			(at 5.06603 0.06731 270)
			(unlocked yes)
			(layer "B.SilkS")
			(effects
				(font
					(size 0.7874 0.5842)
					(thickness 0.1524)
				)
				(justify left mirror)
			)
		)
		(property "Value" ""
			(at 0 0 90)
			(layer "B.Fab")
			(effects
				(font
					(size 1.27 1.27)
				)
				(justify mirror)
			)
		)
		(duplicate_pad_numbers_are_jumpers no)
		(fp_line
			(start -0.7874 0.4064)
			(end 0.7874 0.4064)
			(stroke
				(width 0.1524)
				(type default)
			)
			(layer "B.SilkS")
		)
		(fp_line
			(start 0.7874 0.4064)
			(end 0.7874 -0.4064)
			(stroke
				(width 0.1524)
				(type default)
			)
			(layer "B.SilkS")
		)
		(fp_line
			(start -0.7874 -0.4064)
			(end -0.7874 0.4064)
			(stroke
				(width 0.1524)
				(type default)
			)
			(layer "B.SilkS")
		)
		(fp_line
			(start 0.7874 -0.4064)
			(end -0.7874 -0.4064)
			(stroke
				(width 0.1524)
				(type default)
			)
			(layer "B.SilkS")
		)
		(fp_poly
			(pts
				(xy 0.508 0.2794) (xy 0.508 0.2286) (xy 0.635 0.2286) (xy 0.635 -0.254) (xy 0.5334 -0.254) (xy 0.5334 -0.2794)
				(xy -0.5334 -0.2794) (xy -0.5334 -0.254) (xy -0.635 -0.254) (xy -0.635 0.254) (xy -0.5334 0.254)
				(xy -0.5334 0.2794)
			)
			(stroke
				(width 0)
				(type default)
			)
			(fill no)
			(layer "B.CrtYd")
		)
		(pad "1" smd rect
			(at -0.40005 0 90)
			(size 0.4572 0.508)
			(layers "B.Cu" "B.Mask" "B.Paste")
			(net "P3V3_NODE1")
		)
		(pad "2" smd rect
			(at 0.40005 0 90)
			(size 0.4572 0.508)
			(layers "B.Cu" "B.Mask" "B.Paste")
			(net "BMC_ROMA4")
		)
	)
	(footprint ""
		(layer "B.Cu")
		(at 50.659538 -77.804518 -90)
		(property "Reference" "C51"
			(at 32.2707 15.438628 270)
			(unlocked yes)
			(layer "B.SilkS")
			(effects
				(font
					(size 0.7874 0.5842)
					(thickness 0.1524)
				)
				(justify left mirror)
			)
		)
		(property "Value" ""
			(at 0 0 90)
			(layer "B.Fab")
			(effects
				(font
					(size 1.27 1.27)
				)
				(justify mirror)
			)
		)
		(duplicate_pad_numbers_are_jumpers no)
		(fp_line
			(start -0.7874 0.4064)
			(end 0.7874 0.4064)
			(stroke
				(width 0.1524)
				(type default)
			)
			(layer "B.SilkS")
		)
		(fp_line
			(start 0.7874 0.4064)
			(end 0.7874 -0.4064)
			(stroke
				(width 0.1524)
				(type default)
			)
			(layer "B.SilkS")
		)
		(fp_line
			(start 0 0.381)
			(end 0 -0.381)
			(stroke
				(width 0.1524)
				(type default)
			)
			(layer "B.SilkS")
		)
		(fp_line
			(start -0.7874 -0.4064)
			(end -0.7874 0.4064)
			(stroke
				(width 0.1524)
				(type default)
			)
			(layer "B.SilkS")
		)
		(fp_line
			(start 0.7874 -0.4064)
			(end -0.7874 -0.4064)
			(stroke
				(width 0.1524)
				(type default)
			)
			(layer "B.SilkS")
		)
		(fp_poly
			(pts
				(xy 0.5334 0.254) (xy 0.635 0.254) (xy 0.635 0.2286) (xy 0.635 -0.254) (xy 0.5334 -0.254) (xy 0.5334 -0.2794)
				(xy -0.5334 -0.2794) (xy -0.5334 -0.254) (xy -0.635 -0.254) (xy -0.635 0.254) (xy -0.5334 0.254)
				(xy -0.5334 0.2794) (xy 0.508 0.2794) (xy 0.5334 0.2794)
			)
			(stroke
				(width 0)
				(type default)
			)
			(fill no)
			(layer "B.CrtYd")
		)
		(pad "1" smd rect
			(at -0.40005 0 90)
			(size 0.4572 0.508)
			(layers "B.Cu" "B.Mask" "B.Paste")
			(net "P1V05_NODE1")
		)
		(pad "2" smd rect
			(at 0.40005 0 90)
			(size 0.4572 0.508)
			(layers "B.Cu" "B.Mask" "B.Paste")
			(net "GND")
		)
	)
)
